(kicad_pcb
	(version 20260206)
	(generator "pcbnew")
	(generator_version "10.0")
	(general
		(thickness 1.6)
		(legacy_teardrops no)
	)
	(paper "A4")
	(title_block
		(title "peb — Lightning_PEB_BRD.brd")
		(comment 1 "Lightning (Wiwynn / Facebook NVMe JBOF) / footprints 2536-2543 of 2563")
	)
	(layers
		(0 "F.Cu" signal "TOP")
		(4 "In1.Cu" signal "L2GND")
		(6 "In2.Cu" signal "L3")
		(8 "In3.Cu" signal "L4VCC")
		(10 "In4.Cu" signal "L5VCC")
		(12 "In5.Cu" signal "L6")
		(14 "In6.Cu" signal "L7GND")
		(2 "B.Cu" signal "BOTTOM")
		(9 "F.Adhes" user "F.Adhesive")
		(11 "B.Adhes" user "B.Adhesive")
		(13 "F.Paste" user "Package Geometry/Pastemask Top")
		(15 "B.Paste" user "Package Geometry/Pastemask Bottom")
		(5 "F.SilkS" user "Ref Des/Silkscreen Top")
		(7 "B.SilkS" user "Ref Des/Silkscreen Bottom")
		(1 "F.Mask" user "Board Geometry/Soldermask Top")
		(3 "B.Mask" user "Board Geometry/Soldermask Bottom")
		(17 "Dwgs.User" user "User.Drawings")
		(19 "Cmts.User" user "User.Comments")
		(21 "Eco1.User" user "User.Eco1")
		(23 "Eco2.User" user "User.Eco2")
		(25 "Edge.Cuts" user "Board Geometry/Outline")
		(27 "Margin" user)
		(31 "F.CrtYd" user "Package Geometry/Place Bound Top")
		(29 "B.CrtYd" user "Package Geometry/Place Bound Bottom")
		(35 "F.Fab" user "Ref Des/Assembly Top")
		(33 "B.Fab" user "Ref Des/Assembly Bottom")
	)
	(footprint ""
		(layer "B.Cu")
		(at 259.176266 -6.92658 90)
		(property "Reference" "U15"
			(at 0 0 90)
			(layer "B.SilkS")
			(hide yes)
			(effects
				(font
					(size 1.27 1.27)
				)
				(justify mirror)
			)
		)
		(property "Value" "TMP421AIDCNRG4-GP"
			(at 5.08 -8.5852 90)
			(unlocked yes)
			(layer "B.Fab")
			(hide yes)
			(effects
				(font
					(size 1.016 1.016)
					(thickness 0.1524)
				)
				(justify mirror)
			)
		)
		(property "Device Type" "SOT23-8PH58"
			(at 5.08 -10.1092 90)
			(unlocked yes)
			(layer "B.Fab")
			(hide yes)
			(effects
				(font
					(size 1.016 1.016)
					(thickness 0.1524)
				)
				(justify mirror)
			)
		)
		(duplicate_pad_numbers_are_jumpers no)
		(fp_line
			(start 1.8796 -0.5588)
			(end -1.8796 -0.5588)
			(stroke
				(width 0.1524)
				(type default)
			)
			(layer "B.SilkS")
		)
		(fp_line
			(start -1.8796 -0.5588)
			(end -1.8796 0.5588)
			(stroke
				(width 0.1524)
				(type default)
			)
			(layer "B.SilkS")
		)
		(fp_line
			(start 1.8796 -0.254)
			(end 1.6256 0)
			(stroke
				(width 0.1524)
				(type default)
			)
			(layer "B.SilkS")
		)
		(fp_line
			(start 1.6256 0)
			(end 1.8796 0.254)
			(stroke
				(width 0.1524)
				(type default)
			)
			(layer "B.SilkS")
		)
		(fp_line
			(start 1.8796 0.5588)
			(end 1.8796 -0.5588)
			(stroke
				(width 0.1524)
				(type default)
			)
			(layer "B.SilkS")
		)
		(fp_line
			(start 1.7018 0.5588)
			(end 1.7018 2.1082)
			(stroke
				(width 0.508)
				(type default)
			)
			(layer "B.SilkS")
		)
		(fp_line
			(start -1.8796 0.5588)
			(end 1.8796 0.5588)
			(stroke
				(width 0.1524)
				(type default)
			)
			(layer "B.SilkS")
		)
		(fp_poly
			(pts
				(xy 1.15316 0.5588) (xy -1.8796 0.5588) (xy -1.8796 -0.5588) (xy 1.15316 -0.5588)
			)
			(stroke
				(width 0)
				(type default)
			)
			(fill yes)
			(layer "B.SilkS")
		)
		(fp_rect
			(start 1.9558 2.3622)
			(end -1.9558 -2.3622)
			(stroke
				(width 0)
				(type default)
			)
			(fill no)
			(layer "B.CrtYd")
		)
		(fp_poly
			(pts
				(xy 1.9558 -2.3622) (xy -1.9558 -2.3622) (xy -1.9558 2.3622) (xy 1.9558 2.3622)
			)
			(stroke
				(width 0)
				(type default)
			)
			(fill no)
			(layer "B.Fab")
		)
		(pad "1" smd rect
			(at 0.97536 1.3462 270)
			(size 0.3556 1.016)
			(layers "B.Cu" "B.Mask" "B.Paste")
			(net "TEMP_SENSOR_DXP")
		)
		(pad "2" smd rect
			(at 0.32512 1.3462 270)
			(size 0.3556 1.016)
			(layers "B.Cu" "B.Mask" "B.Paste")
			(net "TEMP_SENSOR_DXN")
		)
		(pad "3" smd rect
			(at -0.32512 1.3462 270)
			(size 0.3556 1.016)
			(layers "B.Cu" "B.Mask" "B.Paste")
			(net "TEMP_1_A1")
		)
		(pad "4" smd rect
			(at -0.97409 1.3462 270)
			(size 0.3556 1.016)
			(layers "B.Cu" "B.Mask" "B.Paste")
			(net "TEMP_1_A0")
		)
		(pad "5" smd rect
			(at -0.97409 -1.3462 270)
			(size 0.3556 1.016)
			(layers "B.Cu" "B.Mask" "B.Paste")
			(net "GND")
		)
		(pad "6" smd rect
			(at -0.32512 -1.3462 270)
			(size 0.3556 1.016)
			(layers "B.Cu" "B.Mask" "B.Paste")
			(net "TEMP_1_SDA")
		)
		(pad "7" smd rect
			(at 0.32512 -1.3462 270)
			(size 0.3556 1.016)
			(layers "B.Cu" "B.Mask" "B.Paste")
			(net "TEMP_1_SCL")
		)
		(pad "8" smd rect
			(at 0.97536 -1.3462 270)
			(size 0.3556 1.016)
			(layers "B.Cu" "B.Mask" "B.Paste")
			(net "P3V3_STBY")
		)
	)
	(footprint ""
		(layer "B.Cu")
		(at 178.0794 -66.167)
		(property "Reference" "PG23"
			(at 0 0 0)
			(layer "B.SilkS")
			(hide yes)
			(effects
				(font
					(size 1.27 1.27)
				)
				(justify mirror)
			)
		)
		(property "Value" "GAP-CLOSE-PWR-3-GP"
			(at -0.0254 -6.5786 0)
			(unlocked yes)
			(layer "B.Fab")
			(hide yes)
			(effects
				(font
					(size 1.016 1.016)
					(thickness 0.1524)
				)
				(justify mirror)
			)
		)
		(property "Device Type" "GAP-CLOSE-PWR-3"
			(at -0.0254 -8.255 0)
			(unlocked yes)
			(layer "B.Fab")
			(hide yes)
			(effects
				(font
					(size 1.016 1.016)
					(thickness 0.1524)
				)
				(justify mirror)
			)
		)
		(duplicate_pad_numbers_are_jumpers no)
		(fp_rect
			(start 0.7112 0.4572)
			(end -0.7112 -0.4572)
			(stroke
				(width 0)
				(type default)
			)
			(fill no)
			(layer "B.CrtYd")
		)
		(fp_poly
			(pts
				(xy 0.7112 -0.4572) (xy -0.7112 -0.4572) (xy -0.7112 0.4572) (xy 0.7112 0.4572)
			)
			(stroke
				(width 0)
				(type default)
			)
			(fill no)
			(layer "B.Fab")
		)
		(pad "1" smd rect
			(at 0.3048 0 180)
			(size 0.6604 0.762)
			(layers "B.Cu" "B.Mask" "B.Paste")
			(net "DUT_AVD_PCIE")
		)
		(pad "2" smd rect
			(at -0.3048 0 180)
			(size 0.6604 0.762)
			(layers "B.Cu" "B.Mask" "B.Paste")
			(net "P0V9")
		)
	)
	(footprint ""
		(layer "B.Cu")
		(at 232.6005 -34.0106 180)
		(property "Reference" "TP198"
			(at 0 0 0)
			(layer "B.SilkS")
			(hide yes)
			(effects
				(font
					(size 1.27 1.27)
				)
				(justify mirror)
			)
		)
		(property "Value" "TPAD28-2-GP"
			(at 0.0127 -1.6637 180)
			(unlocked yes)
			(layer "B.Fab")
			(hide yes)
			(effects
				(font
					(size 1.016 1.016)
					(thickness 0.1524)
				)
				(justify mirror)
			)
		)
		(property "Device Type" "TPAD28"
			(at 0.0127 -3.1877 180)
			(unlocked yes)
			(layer "B.Fab")
			(hide yes)
			(effects
				(font
					(size 1.016 1.016)
					(thickness 0.1524)
				)
				(justify mirror)
			)
		)
		(duplicate_pad_numbers_are_jumpers no)
		(fp_poly
			(pts
				(arc
					(start -0.3556 0)
					(mid 0.3556 0)
					(end -0.3556 0)
				)
			)
			(stroke
				(width 0)
				(type default)
			)
			(fill no)
			(layer "B.CrtYd")
		)
		(fp_poly
			(pts
				(arc
					(start -0.6096 0)
					(mid 0.6096 0)
					(end -0.6096 0)
				)
			)
			(stroke
				(width 0)
				(type default)
			)
			(fill no)
			(layer "B.Fab")
		)
		(pad "1" smd circle
			(at 0 0)
			(size 0.7112 0.7112)
			(layers "B.Cu" "B.Mask" "B.Paste")
			(net "RMII_TXD_0")
		)
	)
	(footprint ""
		(layer "B.Cu")
		(at 124.37872 -33.47847 180)
		(property "Reference" "C129"
			(at 0 0 0)
			(layer "B.SilkS")
			(hide yes)
			(effects
				(font
					(size 1.27 1.27)
				)
				(justify mirror)
			)
		)
		(property "Value" "SCD1U10V2KX-5GP"
			(at -1.1811 -2.7051 180)
			(unlocked yes)
			(layer "B.Fab")
			(hide yes)
			(effects
				(font
					(size 1.016 1.016)
					(thickness 0.1524)
				)
				(justify mirror)
			)
		)
		(property "Device Type" "C402H22"
			(at -1.1811 -4.2291 180)
			(unlocked yes)
			(layer "B.Fab")
			(hide yes)
			(effects
				(font
					(size 1.016 1.016)
					(thickness 0.1524)
				)
				(justify mirror)
			)
		)
		(duplicate_pad_numbers_are_jumpers no)
		(fp_rect
			(start 0.4318 0.9525)
			(end -0.4318 -0.9525)
			(stroke
				(width 0)
				(type default)
			)
			(fill no)
			(layer "B.CrtYd")
		)
		(fp_rect
			(start 0.4318 0.9525)
			(end -0.4318 -0.9525)
			(stroke
				(width 0)
				(type default)
			)
			(fill no)
			(layer "B.Fab")
		)
		(pad "1" smd custom
			(at 0 -0.4445)
			(size 0.1524 0.1524)
			(layers "B.Cu" "B.Mask" "B.Paste")
			(net "GND")
			(options
				(clearance outline)
				(anchor circle)
			)
			(primitives
				(gr_poly
					(pts
						(arc
							(start 0.3048 0.2032)
							(mid 0.275042 0.275042)
							(end 0.2032 0.3048)
						)
						(arc
							(start -0.2032 0.3048)
							(mid -0.275042 0.275042)
							(end -0.3048 0.2032)
						)
						(arc
							(start -0.3048 -0.2032)
							(mid -0.275042 -0.275042)
							(end -0.2032 -0.3048)
						)
						(arc
							(start 0.2032 -0.3048)
							(mid 0.275042 -0.275042)
							(end 0.3048 -0.2032)
						)
					)
					(width 0)
					(fill yes)
				)
			)
		)
		(pad "2" smd custom
			(at 0 0.4445)
			(size 0.1524 0.1524)
			(layers "B.Cu" "B.Mask" "B.Paste")
			(net "P3V3_STBY")
			(options
				(clearance outline)
				(anchor circle)
			)
			(primitives
				(gr_poly
					(pts
						(arc
							(start 0.3048 0.2032)
							(mid 0.275042 0.275042)
							(end 0.2032 0.3048)
						)
						(arc
							(start -0.2032 0.3048)
							(mid -0.275042 0.275042)
							(end -0.3048 0.2032)
						)
						(arc
							(start -0.3048 -0.2032)
							(mid -0.275042 -0.275042)
							(end -0.2032 -0.3048)
						)
						(arc
							(start 0.2032 -0.3048)
							(mid 0.275042 -0.275042)
							(end 0.3048 -0.2032)
						)
					)
					(width 0)
					(fill yes)
				)
			)
		)
	)
	(footprint ""
		(layer "B.Cu")
		(at 52.343304 -51.5874)
		(property "Reference" "R649"
			(at 0 0 0)
			(layer "B.SilkS")
			(hide yes)
			(effects
				(font
					(size 1.27 1.27)
				)
				(justify mirror)
			)
		)
		(property "Value" "0R2J-2-GP"
			(at -0.064008 -3.993896 0)
			(unlocked yes)
			(layer "B.Fab")
			(hide yes)
			(effects
				(font
					(size 1.016 1.016)
					(thickness 0.1524)
				)
				(justify mirror)
			)
		)
		(property "Device Type" "R402H16"
			(at -0.064008 -5.517896 0)
			(unlocked yes)
			(layer "B.Fab")
			(hide yes)
			(effects
				(font
					(size 1.016 1.016)
					(thickness 0.1524)
				)
				(justify mirror)
			)
		)
		(duplicate_pad_numbers_are_jumpers no)
		(fp_line
			(start -0.508 -0.9398)
			(end 0.508 -0.9398)
			(stroke
				(width 0.1524)
				(type default)
			)
			(layer "B.SilkS")
		)
		(fp_line
			(start 0.508 -0.9398)
			(end 0.508 0.9398)
			(stroke
				(width 0.1524)
				(type default)
			)
			(layer "B.SilkS")
		)
		(fp_rect
			(start 0.508 0.9398)
			(end -0.508 -0.9398)
			(stroke
				(width 0)
				(type default)
			)
			(fill no)
			(layer "B.CrtYd")
		)
		(fp_rect
			(start 0.508 0.9398)
			(end -0.508 -0.9398)
			(stroke
				(width 0)
				(type default)
			)
			(fill no)
			(layer "B.Fab")
		)
		(pad "1" smd custom
			(at 0 -0.4445 180)
			(size 0.1397 0.1397)
			(layers "B.Cu" "B.Mask" "B.Paste")
			(net "USB_P2_DN")
			(options
				(clearance outline)
				(anchor circle)
			)
			(primitives
				(gr_poly
					(pts
						(arc
							(start -0.1778 0.2794)
							(mid -0.249642 0.249642)
							(end -0.2794 0.1778)
						)
						(arc
							(start -0.2794 -0.1778)
							(mid -0.249642 -0.249642)
							(end -0.1778 -0.2794)
						)
						(arc
							(start 0.1778 -0.2794)
							(mid 0.249642 -0.249642)
							(end 0.2794 -0.1778)
						)
						(arc
							(start 0.2794 0.1778)
							(mid 0.249642 0.249642)
							(end 0.1778 0.2794)
						)
					)
					(width 0)
					(fill yes)
				)
			)
		)
		(pad "2" smd custom
			(at 0 0.4445 180)
			(size 0.1397 0.1397)
			(layers "B.Cu" "B.Mask" "B.Paste")
			(net "USB_DN_R")
			(options
				(clearance outline)
				(anchor circle)
			)
			(primitives
				(gr_poly
					(pts
						(arc
							(start -0.1778 0.2794)
							(mid -0.249642 0.249642)
							(end -0.2794 0.1778)
						)
						(arc
							(start -0.2794 -0.1778)
							(mid -0.249642 -0.249642)
							(end -0.1778 -0.2794)
						)
						(arc
							(start 0.1778 -0.2794)
							(mid 0.249642 -0.249642)
							(end 0.2794 -0.1778)
						)
						(arc
							(start 0.2794 0.1778)
							(mid 0.249642 0.249642)
							(end 0.1778 0.2794)
						)
					)
					(width 0)
					(fill yes)
				)
			)
		)
	)
	(footprint ""
		(layer "B.Cu")
		(at 227.6856 -37.9984 -90)
		(property "Reference" "C570"
			(at 0 0 90)
			(layer "B.SilkS")
			(hide yes)
			(effects
				(font
					(size 1.27 1.27)
				)
				(justify mirror)
			)
		)
		(property "Value" "SCD1U16V1KX-1-GP"
			(at 2.8321 -1.7399 270)
			(unlocked yes)
			(layer "B.Fab")
			(hide yes)
			(effects
				(font
					(size 1.016 1.016)
					(thickness 0.1524)
				)
				(justify mirror)
			)
		)
		(property "Device Type" "C0201H13"
			(at 2.8321 -3.2639 270)
			(unlocked yes)
			(layer "B.Fab")
			(hide yes)
			(effects
				(font
					(size 1.016 1.016)
					(thickness 0.1524)
				)
				(justify mirror)
			)
		)
		(duplicate_pad_numbers_are_jumpers no)
		(fp_rect
			(start 0.2794 0.6477)
			(end -0.2794 -0.6477)
			(stroke
				(width 0)
				(type default)
			)
			(fill no)
			(layer "B.CrtYd")
		)
		(fp_rect
			(start 0.2794 0.6477)
			(end -0.2794 -0.6477)
			(stroke
				(width 0)
				(type default)
			)
			(fill no)
			(layer "B.Fab")
		)
		(pad "1" smd custom
			(at 0 -0.2794 90)
			(size 0.0762 0.0762)
			(layers "B.Cu" "B.Mask" "B.Paste")
			(net "DUT_AVD_PCIE")
			(options
				(clearance outline)
				(anchor circle)
			)
			(primitives
				(gr_poly
					(pts
						(arc
							(start 0.1524 0.127)
							(mid 0.137521 0.162921)
							(end 0.1016 0.1778)
						)
						(arc
							(start -0.1016 0.1778)
							(mid -0.137521 0.162921)
							(end -0.1524 0.127)
						)
						(arc
							(start -0.1524 -0.127)
							(mid -0.137521 -0.162921)
							(end -0.1016 -0.1778)
						)
						(arc
							(start 0.1016 -0.1778)
							(mid 0.137521 -0.162921)
							(end 0.1524 -0.127)
						)
					)
					(width 0)
					(fill yes)
				)
			)
		)
		(pad "2" smd custom
			(at 0 0.2794 90)
			(size 0.0762 0.0762)
			(layers "B.Cu" "B.Mask" "B.Paste")
			(net "GND")
			(options
				(clearance outline)
				(anchor circle)
			)
			(primitives
				(gr_poly
					(pts
						(arc
							(start 0.1524 0.127)
							(mid 0.137521 0.162921)
							(end 0.1016 0.1778)
						)
						(arc
							(start -0.1016 0.1778)
							(mid -0.137521 0.162921)
							(end -0.1524 0.127)
						)
						(arc
							(start -0.1524 -0.127)
							(mid -0.137521 -0.162921)
							(end -0.1016 -0.1778)
						)
						(arc
							(start 0.1016 -0.1778)
							(mid 0.137521 -0.162921)
							(end 0.1524 -0.127)
						)
					)
					(width 0)
					(fill yes)
				)
			)
		)
	)
	(footprint ""
		(layer "B.Cu")
		(at 228.6254 -49.001172 90)
		(property "Reference" "C493"
			(at 0 0 90)
			(layer "B.SilkS")
			(hide yes)
			(effects
				(font
					(size 1.27 1.27)
				)
				(justify mirror)
			)
		)
		(property "Value" "SCD1U16V1KX-1-GP"
			(at 2.8321 -1.7399 90)
			(unlocked yes)
			(layer "B.Fab")
			(hide yes)
			(effects
				(font
					(size 1.016 1.016)
					(thickness 0.1524)
				)
				(justify mirror)
			)
		)
		(property "Device Type" "C0201H13"
			(at 2.8321 -3.2639 90)
			(unlocked yes)
			(layer "B.Fab")
			(hide yes)
			(effects
				(font
					(size 1.016 1.016)
					(thickness 0.1524)
				)
				(justify mirror)
			)
		)
		(duplicate_pad_numbers_are_jumpers no)
		(fp_rect
			(start 0.2794 0.6477)
			(end -0.2794 -0.6477)
			(stroke
				(width 0)
				(type default)
			)
			(fill no)
			(layer "B.CrtYd")
		)
		(fp_rect
			(start 0.2794 0.6477)
			(end -0.2794 -0.6477)
			(stroke
				(width 0)
				(type default)
			)
			(fill no)
			(layer "B.Fab")
		)
		(pad "1" smd custom
			(at 0 -0.2794 270)
			(size 0.0762 0.0762)
			(layers "B.Cu" "B.Mask" "B.Paste")
			(net "DUT_AVD_PCIE")
			(options
				(clearance outline)
				(anchor circle)
			)
			(primitives
				(gr_poly
					(pts
						(arc
							(start 0.1524 0.127)
							(mid 0.137521 0.162921)
							(end 0.1016 0.1778)
						)
						(arc
							(start -0.1016 0.1778)
							(mid -0.137521 0.162921)
							(end -0.1524 0.127)
						)
						(arc
							(start -0.1524 -0.127)
							(mid -0.137521 -0.162921)
							(end -0.1016 -0.1778)
						)
						(arc
							(start 0.1016 -0.1778)
							(mid 0.137521 -0.162921)
							(end 0.1524 -0.127)
						)
					)
					(width 0)
					(fill yes)
				)
			)
		)
		(pad "2" smd custom
			(at 0 0.2794 270)
			(size 0.0762 0.0762)
			(layers "B.Cu" "B.Mask" "B.Paste")
			(net "GND")
			(options
				(clearance outline)
				(anchor circle)
			)
			(primitives
				(gr_poly
					(pts
						(arc
							(start 0.1524 0.127)
							(mid 0.137521 0.162921)
							(end 0.1016 0.1778)
						)
						(arc
							(start -0.1016 0.1778)
							(mid -0.137521 0.162921)
							(end -0.1524 0.127)
						)
						(arc
							(start -0.1524 -0.127)
							(mid -0.137521 -0.162921)
							(end -0.1016 -0.1778)
						)
						(arc
							(start 0.1016 -0.1778)
							(mid 0.137521 -0.162921)
							(end 0.1524 -0.127)
						)
					)
					(width 0)
					(fill yes)
				)
			)
		)
	)
	(footprint ""
		(layer "B.Cu")
		(at 231.394 -23.241 180)
		(property "Reference" "R790"
			(at 0 0 0)
			(layer "B.SilkS")
			(hide yes)
			(effects
				(font
					(size 1.27 1.27)
				)
				(justify mirror)
			)
		)
		(property "Value" "4K7R2F-GP"
			(at -0.064008 -3.993896 180)
			(unlocked yes)
			(layer "B.Fab")
			(hide yes)
			(effects
				(font
					(size 1.016 1.016)
					(thickness 0.1524)
				)
				(justify mirror)
			)
		)
		(property "Device Type" "R402H16"
			(at -0.064008 -5.517896 180)
			(unlocked yes)
			(layer "B.Fab")
			(hide yes)
			(effects
				(font
					(size 1.016 1.016)
					(thickness 0.1524)
				)
				(justify mirror)
			)
		)
		(duplicate_pad_numbers_are_jumpers no)
		(fp_line
			(start 0.508 -0.9398)
			(end 0.508 0.9398)
			(stroke
				(width 0.1524)
				(type default)
			)
			(layer "B.SilkS")
		)
		(fp_line
			(start -0.508 -0.9398)
			(end 0.508 -0.9398)
			(stroke
				(width 0.1524)
				(type default)
			)
			(layer "B.SilkS")
		)
		(fp_rect
			(start 0.508 0.9398)
			(end -0.508 -0.9398)
			(stroke
				(width 0)
				(type default)
			)
			(fill no)
			(layer "B.CrtYd")
		)
		(fp_rect
			(start 0.508 0.9398)
			(end -0.508 -0.9398)
			(stroke
				(width 0)
				(type default)
			)
			(fill no)
			(layer "B.Fab")
		)
		(pad "1" smd custom
			(at 0 -0.4445)
			(size 0.1397 0.1397)
			(layers "B.Cu" "B.Mask" "B.Paste")
			(net "BOOTSTRAP10")
			(options
				(clearance outline)
				(anchor circle)
			)
			(primitives
				(gr_poly
					(pts
						(arc
							(start -0.1778 0.2794)
							(mid -0.249642 0.249642)
							(end -0.2794 0.1778)
						)
						(arc
							(start -0.2794 -0.1778)
							(mid -0.249642 -0.249642)
							(end -0.1778 -0.2794)
						)
						(arc
							(start 0.1778 -0.2794)
							(mid 0.249642 -0.249642)
							(end 0.2794 -0.1778)
						)
						(arc
							(start 0.2794 0.1778)
							(mid 0.249642 0.249642)
							(end 0.1778 0.2794)
						)
					)
					(width 0)
					(fill yes)
				)
			)
		)
		(pad "2" smd custom
			(at 0 0.4445)
			(size 0.1397 0.1397)
			(layers "B.Cu" "B.Mask" "B.Paste")
			(net "BOOTSTRAP_R_10")
			(options
				(clearance outline)
				(anchor circle)
			)
			(primitives
				(gr_poly
					(pts
						(arc
							(start -0.1778 0.2794)
							(mid -0.249642 0.249642)
							(end -0.2794 0.1778)
						)
						(arc
							(start -0.2794 -0.1778)
							(mid -0.249642 -0.249642)
							(end -0.1778 -0.2794)
						)
						(arc
							(start 0.1778 -0.2794)
							(mid 0.249642 -0.249642)
							(end 0.2794 -0.1778)
						)
						(arc
							(start 0.2794 0.1778)
							(mid 0.249642 0.249642)
							(end 0.1778 0.2794)
						)
					)
					(width 0)
					(fill yes)
				)
			)
		)
	)
)
